# BASEBOARD_FAB2 (Tioga Pass) — schematic netlist excerpt (pin names and nets, part order shuffled) for the footprints in the layout excerpt that follows; sources: Cadence DE-HDL packaged netlist, KiCad conversion of Wiwynn_Tioga_Pass_MB.brd

C5G113  CAP_A  22.0UF 4V 20% X6S  pkg 0603V  page 243 : A = PVDDQ_KLM ; B = GND
R2U48  RES  4.75K 1% CHIP  pkg 0402  page 119 : A = P3V3_STBY ; B = FM_SLT_CFG2_R
C1M5  CAPP  68UF 16V 20% TANT  pkg 3018  page 195 : A = P12V_STBY ; B = GND

(kicad_pcb
	(version 20260206)
	(generator "pcbnew")
	(generator_version "10.0")
	(general
		(thickness 1.6)
		(legacy_teardrops no)
	)
	(paper "A4")
	(title_block
		(title "Wiwynn_Tioga_Pass_MB.brd")
		(comment 1 "Tioga Pass / footprints 3019-3021 of 4770")
	)
	(layers
		(0 "F.Cu" signal "TOP")
		(4 "In1.Cu" signal "L2GND")
		(6 "In2.Cu" signal "L3")
		(8 "In3.Cu" signal "L4GND")
		(10 "In4.Cu" signal "L5")
		(12 "In5.Cu" signal "L6GND")
		(14 "In6.Cu" signal "L7VCC")
		(16 "In7.Cu" signal "L8VCC")
		(18 "In8.Cu" signal "L9GND")
		(20 "In9.Cu" signal "L10")
		(22 "In10.Cu" signal "L11GND")
		(24 "In11.Cu" signal "L12")
		(26 "In12.Cu" signal "L13GND")
		(2 "B.Cu" signal "BOTTOM")
		(9 "F.Adhes" user "F.Adhesive")
		(11 "B.Adhes" user "B.Adhesive")
		(13 "F.Paste" user "Package Geometry/Pastemask Top")
		(15 "B.Paste" user "Package Geometry/Pastemask Bottom")
		(5 "F.SilkS" user "Ref Des/Silkscreen Top")
		(7 "B.SilkS" user "Ref Des/Silkscreen Bottom")
		(1 "F.Mask" user "Board Geometry/Soldermask Top")
		(3 "B.Mask" user "Board Geometry/Soldermask Bottom")
		(17 "Dwgs.User" user "User.Drawings")
		(19 "Cmts.User" user "User.Comments")
		(21 "Eco1.User" user "User.Eco1")
		(23 "Eco2.User" user "User.Eco2")
		(25 "Edge.Cuts" user "Board Geometry/Outline")
		(27 "Margin" user)
		(31 "F.CrtYd" user "Package Geometry/Place Bound Top")
		(29 "B.CrtYd" user "Package Geometry/Place Bound Bottom")
		(35 "F.Fab" user "Ref Des/Assembly Top")
		(33 "B.Fab" user "Ref Des/Assembly Bottom")
	)
	(footprint ""
		(layer "B.Cu")
		(at 83.856068 -140.208 -90)
		(property "Reference" "C5G113"
			(at -1.14681 0.76708 0)
			(unlocked yes)
			(layer "B.SilkS")
			(effects
				(font
					(size 0.7874 0.5842)
					(thickness 0.1524)
				)
				(justify mirror)
			)
		)
		(property "Value" ""
			(at 0 0 90)
			(layer "B.Fab")
			(effects
				(font
					(size 1.27 1.27)
				)
				(justify mirror)
			)
		)
		(duplicate_pad_numbers_are_jumpers no)
		(fp_rect
			(start 0.4953 1.6002)
			(end -0.4953 -0.2032)
			(stroke
				(width 0)
				(type default)
			)
			(fill no)
			(layer "B.CrtYd")
		)
		(fp_line
			(start -0.4953 1.6002)
			(end 0.4953 1.6002)
			(stroke
				(width 0.1)
				(type default)
			)
			(layer "B.Fab")
		)
		(fp_line
			(start 0.4953 1.6002)
			(end 0.4953 -0.2032)
			(stroke
				(width 0.1)
				(type default)
			)
			(layer "B.Fab")
		)
		(fp_line
			(start -0.4953 -0.2032)
			(end -0.4953 1.6002)
			(stroke
				(width 0.1)
				(type default)
			)
			(layer "B.Fab")
		)
		(fp_line
			(start 0.4953 -0.2032)
			(end -0.4953 -0.2032)
			(stroke
				(width 0.1)
				(type default)
			)
			(layer "B.Fab")
		)
		(pad "1" smd rect
			(at 0 0 90)
			(size 0.762 0.889)
			(layers "B.Cu" "B.Mask" "B.Paste")
			(net "PVDDQ_KLM")
		)
		(pad "2" smd rect
			(at 0 1.397 90)
			(size 0.762 0.889)
			(layers "B.Cu" "B.Mask" "B.Paste")
			(net "GND")
		)
		(zone
			(layer "B.Cu")
			(hatch none 0.5)
			(connect_pads
				(clearance 0)
			)
			(min_thickness 0.25)
			(keepout
				(tracks not_allowed)
				(vias allowed)
				(pads allowed)
				(copperpour not_allowed)
				(footprints allowed)
			)
			(placement
				(enabled no)
				(sheetname "")
			)
			(fill
				(thermal_gap 0.5)
				(thermal_bridge_width 0.5)
				(island_removal_mode 0)
			)
			(polygon
				(pts
					(xy 82.903568 -139.827) (xy 83.411568 -139.827) (xy 83.411568 -140.589) (xy 82.903568 -140.589)
				)
			)
		)
	)
	(footprint ""
		(layer "B.Cu")
		(at 464.5025 -4.445 90)
		(property "Reference" "R2U48"
			(at 0 0 90)
			(layer "B.SilkS")
			(hide yes)
			(effects
				(font
					(size 1.27 1.27)
				)
				(justify mirror)
			)
		)
		(property "Value" ""
			(at 0 0 90)
			(layer "B.Fab")
			(effects
				(font
					(size 1.27 1.27)
				)
				(justify mirror)
			)
		)
		(duplicate_pad_numbers_are_jumpers no)
		(fp_poly
			(pts
				(xy 0.2794 -0.1016) (xy -0.2794 -0.1016) (xy -0.2794 0.9906) (xy 0.2794 0.9906)
			)
			(stroke
				(width 0)
				(type default)
			)
			(fill no)
			(layer "B.CrtYd")
		)
		(fp_line
			(start 0.2794 -0.1016)
			(end 0.2794 0.9906)
			(stroke
				(width 0.1)
				(type default)
			)
			(layer "B.Fab")
		)
		(fp_line
			(start -0.2794 -0.1016)
			(end 0.2794 -0.1016)
			(stroke
				(width 0.1)
				(type default)
			)
			(layer "B.Fab")
		)
		(fp_line
			(start 0.2794 0.9906)
			(end -0.2794 0.9906)
			(stroke
				(width 0.1)
				(type default)
			)
			(layer "B.Fab")
		)
		(fp_line
			(start -0.2794 0.9906)
			(end -0.2794 -0.1016)
			(stroke
				(width 0.1)
				(type default)
			)
			(layer "B.Fab")
		)
		(pad "1" smd rect
			(at 0 0 270)
			(size 0.508 0.508)
			(layers "B.Cu" "B.Mask" "B.Paste")
			(net "P3V3_STBY")
		)
		(pad "2" smd rect
			(at 0 0.889 270)
			(size 0.508 0.508)
			(layers "B.Cu" "B.Mask" "B.Paste")
			(net "FM_SLT_CFG2_R")
		)
		(zone
			(layer "B.Cu")
			(hatch none 0.5)
			(connect_pads
				(clearance 0)
			)
			(min_thickness 0.25)
			(keepout
				(tracks allowed)
				(vias not_allowed)
				(pads allowed)
				(copperpour not_allowed)
				(footprints allowed)
			)
			(placement
				(enabled no)
				(sheetname "")
			)
			(fill
				(thermal_gap 0.5)
				(thermal_bridge_width 0.5)
				(island_removal_mode 0)
			)
			(polygon
				(pts
					(xy 464.7565 -4.699) (xy 464.7565 -4.191) (xy 465.1375 -4.191) (xy 465.1375 -4.699)
				)
			)
		)
		(zone
			(layer "B.Cu")
			(hatch none 0.5)
			(connect_pads
				(clearance 0)
			)
			(min_thickness 0.25)
			(keepout
				(tracks not_allowed)
				(vias allowed)
				(pads allowed)
				(copperpour not_allowed)
				(footprints allowed)
			)
			(placement
				(enabled no)
				(sheetname "")
			)
			(fill
				(thermal_gap 0.5)
				(thermal_bridge_width 0.5)
				(island_removal_mode 0)
			)
			(polygon
				(pts
					(xy 465.1375 -4.699) (xy 465.1375 -4.191) (xy 464.7565 -4.191) (xy 464.7565 -4.699)
				)
			)
		)
	)
	(footprint ""
		(layer "B.Cu")
		(at 489.0008 -117.7798 -90)
		(property "Reference" "C1M5"
			(at -3.09753 4.2926 0)
			(unlocked yes)
			(layer "B.SilkS")
			(effects
				(font
					(size 0.7874 0.5842)
					(thickness 0.1524)
				)
				(justify mirror)
			)
		)
		(property "Value" ""
			(at 0 0 90)
			(layer "B.Fab")
			(effects
				(font
					(size 1.27 1.27)
				)
				(justify mirror)
			)
		)
		(duplicate_pad_numbers_are_jumpers no)
		(fp_line
			(start -2.286 7.366)
			(end -1.600708 7.366)
			(stroke
				(width 0.1524)
				(type default)
			)
			(layer "B.SilkS")
		)
		(fp_line
			(start -2.286 7.366)
			(end -2.286 1.63195)
			(stroke
				(width 0.1524)
				(type default)
			)
			(layer "B.SilkS")
		)
		(fp_line
			(start 2.286 7.366)
			(end 1.60147 7.366)
			(stroke
				(width 0.1524)
				(type default)
			)
			(layer "B.SilkS")
		)
		(fp_line
			(start 2.286 7.366)
			(end 2.286 1.632712)
			(stroke
				(width 0.1524)
				(type default)
			)
			(layer "B.SilkS")
		)
		(fp_line
			(start -2.504948 1.633728)
			(end -1.6002 1.633728)
			(stroke
				(width 0.1524)
				(type default)
			)
			(layer "B.SilkS")
		)
		(fp_line
			(start 2.563114 1.633728)
			(end 1.6002 1.633728)
			(stroke
				(width 0.1524)
				(type default)
			)
			(layer "B.SilkS")
		)
		(fp_line
			(start -2.504948 -1.616456)
			(end -2.504948 1.633728)
			(stroke
				(width 0.1524)
				(type default)
			)
			(layer "B.SilkS")
		)
		(fp_line
			(start -1.6002 -1.616456)
			(end -2.504948 -1.616456)
			(stroke
				(width 0.1524)
				(type default)
			)
			(layer "B.SilkS")
		)
		(fp_line
			(start 1.6002 -1.616456)
			(end 2.563114 -1.616456)
			(stroke
				(width 0.1524)
				(type default)
			)
			(layer "B.SilkS")
		)
		(fp_line
			(start 2.563114 -1.616456)
			(end 2.563114 1.633728)
			(stroke
				(width 0.1524)
				(type default)
			)
			(layer "B.SilkS")
		)
		(fp_rect
			(start 2.286 7.366)
			(end -2.286 -0.254)
			(stroke
				(width 0)
				(type default)
			)
			(fill no)
			(layer "B.CrtYd")
		)
		(fp_line
			(start -2.286 7.366)
			(end 2.286 7.366)
			(stroke
				(width 0.1)
				(type default)
			)
			(layer "B.Fab")
		)
		(fp_line
			(start 2.286 7.366)
			(end 2.286 -0.254)
			(stroke
				(width 0.1)
				(type default)
			)
			(layer "B.Fab")
		)
		(fp_line
			(start -2.286 -0.254)
			(end -2.286 7.366)
			(stroke
				(width 0.1)
				(type default)
			)
			(layer "B.Fab")
		)
		(fp_line
			(start 2.286 -0.254)
			(end -2.286 -0.254)
			(stroke
				(width 0.1)
				(type default)
			)
			(layer "B.Fab")
		)
		(pad "1" smd rect
			(at 0 0 90)
			(size 2.54 3.048)
			(layers "B.Cu" "B.Mask" "B.Paste")
			(net "P12V_STBY")
		)
		(pad "2" smd rect
			(at 0 7.112 90)
			(size 2.54 3.048)
			(layers "B.Cu" "B.Mask" "B.Paste")
			(net "GND")
		)
	)
)
